#ISCELL
  mstr_misc dns *
  *
#ISCELL
  pure_quanta quanta_title_block_c *
  *
#ISCELL
  pure_quanta_power cad_note *
  *
#ISCELL
  standard offpage *
  page343_i1
#CELL
  pure_quanta mosfet_nch_dual *
  page343_i10
#ISCELL
  pure_quanta_power gnd *
  page343_i100
#CELL
  pure_quanta q_cap *
  page343_i101
#ISCELL
  pure_quanta_power universal_power *
  page343_i102
#ISCELL
  pure_quanta_power gnd *
  page343_i103
#CELL
  pure_quanta q_cap *
  page343_i104
#CELL
  pure_quanta q_res *
  page343_i105
#CELL
  pure_quanta schottky_ac *
  page343_i106
#CELL
  pure_quanta q_res *
  page343_i107
#CELL
  pure_quanta q_cap *
  page343_i108
#ISCELL
  standard offpage *
  page343_i11
#ISCELL
  pure_quanta_power vccaux15 *
  page343_i110
#ISCELL
  pure_quanta_power gnd *
  page343_i111
#CELL
  pure_quanta q_cap *
  page343_i112
#ISCELL
  pure_quanta_power universal_power *
  page343_i113
#ISCELL
  standard offpage *
  page343_i114
#ISCELL
  pure_quanta_power universal_power *
  page343_i115
#CELL
  pure_quanta q_res *
  page343_i116
#ISCELL
  standard offpage *
  page343_i117
#CELL
  pure_quanta q_res *
  page343_i118
#CELL
  pure_quanta q_res *
  page343_i119
#ISCELL
  standard offpage *
  page343_i12
#CELL
  pure_quanta q_res *
  page343_i120
#CELL
  pure_quanta q_res *
  page343_i121
#CELL
  pure_quanta q_res *
  page343_i122
#CELL
  pure_quanta q_res *
  page343_i123
#ISCELL
  standard offpage *
  page343_i124
#ISCELL
  standard offpage *
  page343_i126
#CELL
  pure_quanta q_res *
  page343_i127
#CELL
  pure_quanta q_res *
  page343_i128
#CELL
  pure_quanta q_res *
  page343_i129
#ISCELL
  pure_quanta_power gnd *
  page343_i13
#CELL
  pure_quanta q_res *
  page343_i130
#ISCELL
  standard offpage *
  page343_i131
#CELL
  pure_quanta q_res *
  page343_i14
#ISCELL
  pure_quanta_power universal_power *
  page343_i15
#CELL
  pure_quanta q_res *
  page343_i16
#CELL
  pure_quanta q_res *
  page343_i17
#ISCELL
  pure_quanta_power universal_power *
  page343_i18
#CELL
  pure_quanta mosfet_nch_dual *
  page343_i19
#ISCELL
  standard offpage *
  page343_i2
#ISCELL
  pure_quanta_power gnd *
  page343_i20
#ISCELL
  pure_quanta_power universal_gnd *
  page343_i21
#CELL
  pure_quanta 74lvc2g07dw7 *
  page343_i22
#CELL
  pure_quanta q_cap *
  page343_i23
#ISCELL
  pure_quanta_power universal_gnd *
  page343_i24
#ISCELL
  pure_quanta_power universal_gnd *
  page343_i25
#ISCELL
  pure_quanta_power universal_power *
  page343_i26
#ISCELL
  pure_quanta_power universal_gnd *
  page343_i27
#CELL
  pure_quanta 74lvc2g07dw7 *
  page343_i28
#CELL
  pure_quanta q_cap *
  page343_i29
#ISCELL
  standard offpage *
  page343_i3
#ISCELL
  pure_quanta_power universal_power *
  page343_i30
#CELL
  pure_quanta q_res *
  page343_i31
#ISCELL
  pure_quanta_power gnd *
  page343_i32
#CELL
  pure_quanta q_res *
  page343_i33
#ISCELL
  pure_quanta_power gnd *
  page343_i34
#CELL
  pure_quanta q_res *
  page343_i35
#CELL
  pure_quanta q_res *
  page343_i36
#ISCELL
  standard offpage *
  page343_i37
#ISCELL
  pure_quanta_power gnd *
  page343_i39
#CELL
  pure_quanta q_res *
  page343_i4
#ISCELL
  pure_quanta_power gnd *
  page343_i41
#CELL
  pure_quanta mosfet_nch_dual *
  page343_i42
#CELL
  pure_quanta q_res *
  page343_i43
#ISCELL
  pure_quanta_power universal_power *
  page343_i44
#CELL
  pure_quanta mosfet_nch_dual *
  page343_i45
#ISCELL
  pure_quanta_power gnd *
  page343_i46
#CELL
  pure_quanta diode_tvs *
  page343_i47
#ISCELL
  pure_quanta_power universal_power *
  page343_i48
#CELL
  pure_quanta q_cap *
  page343_i49
#ISCELL
  pure_quanta_power universal_power *
  page343_i5
#CELL
  pure_quanta q_res *
  page343_i50
#CELL
  pure_quanta q_res *
  page343_i51
#ISCELL
  pure_quanta_power gnd *
  page343_i52
#CELL
  pure_quanta q_res *
  page343_i53
#ISCELL
  pure_quanta_power gnd *
  page343_i54
#CELL
  pure_quanta q_cap *
  page343_i55
#CELL
  pure_quanta q_res *
  page343_i56
#ISCELL
  pure_quanta_power universal_power *
  page343_i57
#CELL
  pure_quanta q_res *
  page343_i59
#CELL
  pure_quanta q_res *
  page343_i6
#ISCELL
  standard offpage *
  page343_i61
#ISCELL
  pure_quanta_power gnd *
  page343_i62
#CELL
  pure_quanta q_res *
  page343_i63
#ISCELL
  pure_quanta_power gnd *
  page343_i64
#CELL
  pure_quanta q_cap *
  page343_i65
#CELL
  pure_quanta q_cap *
  page343_i66
#CELL
  pure_quanta max15090bewit *
  page343_i67
#CELL
  pure_quanta q_res *
  page343_i69
#ISCELL
  pure_quanta_power gnd *
  page343_i70
#CELL
  pure_quanta q_res *
  page343_i71
#CELL
  pure_quanta q_cap *
  page343_i72
#CELL
  pure_quanta q_res *
  page343_i73
#CELL
  pure_quanta q_res *
  page343_i74
#CELL
  pure_quanta q_cap *
  page343_i75
#CELL
  pure_quanta q_res *
  page343_i76
#CELL
  pure_quanta q_res *
  page343_i77
#ISCELL
  pure_quanta_power gnd *
  page343_i78
#CELL
  pure_quanta q_res *
  page343_i79
#ISCELL
  pure_quanta_power gnd *
  page343_i8
#CELL
  pure_quanta q_res *
  page343_i80
#ISCELL
  standard offpage *
  page343_i81
#ISCELL
  standard offpage *
  page343_i82
#ISCELL
  standard offpage *
  page343_i83
#CELL
  pure_quanta q_res *
  page343_i84
#ISCELL
  pure_quanta_power gnd *
  page343_i85
#CELL
  pure_quanta q_cap *
  page343_i86
#ISCELL
  pure_quanta_power gnd *
  page343_i87
#CELL
  pure_quanta q_res *
  page343_i88
#CELL
  pure_quanta max15090bewit *
  page343_i89
#CELL
  pure_quanta q_cap *
  page343_i90
#CELL
  pure_quanta q_res *
  page343_i91
#CELL
  pure_quanta schottky_ac *
  page343_i92
#ISCELL
  pure_quanta_power gnd *
  page343_i93
#CELL
  pure_quanta q_res *
  page343_i94
#CELL
  pure_quanta q_cap *
  page343_i95
#CELL
  pure_quanta q_cap *
  page343_i97
#ISCELL
  pure_quanta_power vccaux15 *
  page343_i98
#CELL
  pure_quanta q_cap *
  page343_i99
